(kicad_pcb
	(version 20241229)
	(generator "pcbnew")
	(generator_version "9.0")
	(general
		(thickness 1.62)
		(legacy_teardrops no)
	)
	(paper "A4")
	(title_block
		(title "OCuLink to 10GbE adapter")
		(date "2026-02-23")
		(rev "1.1.0")
		(company "Antmicro Ltd")
		(comment 1 "www.antmicro.com")
		(comment 9 "footprints 53-57 of 510")
	)
	(layers
		(0 "F.Cu" signal)
		(4 "In1.Cu" signal)
		(6 "In2.Cu" signal)
		(8 "In3.Cu" signal)
		(10 "In4.Cu" signal)
		(12 "In5.Cu" signal)
		(14 "In6.Cu" signal)
		(2 "B.Cu" signal)
		(9 "F.Adhes" user "F.Adhesive")
		(11 "B.Adhes" user "B.Adhesive")
		(13 "F.Paste" user)
		(15 "B.Paste" user)
		(5 "F.SilkS" user "F.Silkscreen")
		(7 "B.SilkS" user "B.Silkscreen")
		(1 "F.Mask" user)
		(3 "B.Mask" user)
		(17 "Dwgs.User" user "User.Drawings")
		(19 "Cmts.User" user "User.Comments")
		(21 "Eco1.User" user "User.Eco1")
		(23 "Eco2.User" user "User.Eco2")
		(25 "Edge.Cuts" user)
		(27 "Margin" user)
		(31 "F.CrtYd" user "F.Courtyard")
		(29 "B.CrtYd" user "B.Courtyard")
		(35 "F.Fab" user)
		(33 "B.Fab" user)
	)
	(footprint "antmicro-footprints:FB_0805_2012Metric"
		(layer "F.Cu")
		(at 104.7 113.9 180)
		(descr "FERRITE BEAD 0805")
		(tags "FERRITE BEAD 0805")
		(property "Reference" "FB2"
			(at -1.1 -1 0)
			(layer "F.SilkS")
			(effects
				(font
					(size 0.7 0.7)
					(thickness 0.15)
				)
				(justify right top)
			)
		)
		(property "Value" "FB_330Z_1.5A_Murata-BLM21PG_0805"
			(at 0.001 1.801 0)
			(layer "F.Fab")
			(hide yes)
			(effects
				(font
					(size 0.7 0.7)
					(thickness 0.15)
				)
				(justify right top)
			)
		)
		(property "Datasheet" "https://www.murata.com/products/productdata/8796738977822/ENFA0005.pdf?1653276712000"
			(at 0 0 0)
			(layer "F.Fab")
			(hide yes)
			(effects
				(font
					(size 1.27 1.27)
					(thickness 0.15)
				)
			)
		)
		(property "Description" "Ferrite Bead, 0805 [2012 Metric], 330 ohm, 1.5 A, BLM21P, 0.07 ohm, ± 25%, DC power line"
			(at 0 0 0)
			(layer "F.Fab")
			(hide yes)
			(effects
				(font
					(size 1.27 1.27)
					(thickness 0.15)
				)
			)
		)
		(property "Val" "330Z/1.5A"
			(at 0 0 180)
			(unlocked yes)
			(layer "F.Fab")
			(hide yes)
			(effects
				(font
					(size 1 1)
					(thickness 0.15)
				)
			)
		)
		(property "MPN" "BLM21PG331SN1D"
			(at 0 0 180)
			(unlocked yes)
			(layer "F.Fab")
			(hide yes)
			(effects
				(font
					(size 1 1)
					(thickness 0.15)
				)
			)
		)
		(property "Manufacturer" "Murata"
			(at 0 0 180)
			(unlocked yes)
			(layer "F.Fab")
			(hide yes)
			(effects
				(font
					(size 1 1)
					(thickness 0.15)
				)
			)
		)
		(property "Current" ""
			(at 0 0 180)
			(unlocked yes)
			(layer "F.Fab")
			(hide yes)
			(effects
				(font
					(size 1 1)
					(thickness 0.15)
				)
			)
		)
		(property "Author" "Antmicro"
			(at 0 0 180)
			(unlocked yes)
			(layer "F.Fab")
			(hide yes)
			(effects
				(font
					(size 1 1)
					(thickness 0.15)
				)
			)
		)
		(property "License" "Apache-2.0"
			(at 0 0 180)
			(unlocked yes)
			(layer "F.Fab")
			(hide yes)
			(effects
				(font
					(size 1 1)
					(thickness 0.15)
				)
			)
		)
		(sheetname "/X710-AT2 10GbE/")
		(sheetfile "x710-at2-10gbe.kicad_sch")
		(attr smd)
		(fp_line
			(start -0.299 -0.698)
			(end 0.299 -0.698)
			(stroke
				(width 0.15)
				(type solid)
			)
			(layer "F.SilkS")
		)
		(fp_line
			(start -0.319 0.698)
			(end 0.281 0.698)
			(stroke
				(width 0.15)
				(type solid)
			)
			(layer "F.SilkS")
		)
		(fp_rect
			(start 1.95 -0.9)
			(end -1.95 0.9)
			(stroke
				(width 0.05)
				(type default)
			)
			(fill no)
			(layer "F.CrtYd")
		)
		(fp_line
			(start 0.948 -0.676)
			(end 0.948 0.676)
			(stroke
				(width 0.15)
				(type solid)
			)
			(layer "F.Fab")
		)
		(fp_line
			(start -0.948 0.681)
			(end 0.948 0.681)
			(stroke
				(width 0.15)
				(type solid)
			)
			(layer "F.Fab")
		)
		(fp_line
			(start -0.948 -0.676)
			(end -0.948 0.676)
			(stroke
				(width 0.15)
				(type solid)
			)
			(layer "F.Fab")
		)
		(fp_line
			(start -0.948 -0.681)
			(end 0.948 -0.681)
			(stroke
				(width 0.15)
				(type solid)
			)
			(layer "F.Fab")
		)
		(pad "1" smd roundrect
			(at -1.1 0 180)
			(size 1.2 1.3)
			(layers "F.Cu" "F.Mask" "F.Paste")
			(roundrect_rratio 0.25)
			(net 7 "+3V3")
			(pintype "passive")
		)
		(pad "2" smd roundrect
			(at 1.1 0 180)
			(size 1.2 1.3)
			(layers "F.Cu" "F.Mask" "F.Paste")
			(roundrect_rratio 0.25)
			(net 74 "/X710-AT2 10GbE/3V3_OSC")
			(pintype "passive")
		)
	)
	(footprint "antmicro-footprints:MP_Terminal_M3_THT_7760"
		(layer "F.Cu")
		(at 52.06 139.7)
		(property "Reference" "J4"
			(at -1.68 -1.85 0)
			(unlocked yes)
			(layer "F.SilkS")
			(effects
				(font
					(size 0.7 0.7)
					(thickness 0.15)
				)
				(justify left bottom)
			)
		)
		(property "Value" "MP_Terminal_M3_THT_7760"
			(at -1.68 11.43 0)
			(unlocked yes)
			(layer "F.Fab")
			(hide yes)
			(effects
				(font
					(size 0.7 0.7)
					(thickness 0.15)
				)
				(justify left bottom)
			)
		)
		(property "Datasheet" "https://www.mouser.com/datasheet/2/215/7760-741244.pdf"
			(at 0 0 0)
			(unlocked yes)
			(layer "F.Fab")
			(hide yes)
			(effects
				(font
					(size 0.7 0.7)
					(thickness 0.15)
				)
				(justify left bottom)
			)
		)
		(property "Description" "PCB Terminal, 90° THT, Brass, Tin"
			(at 0 0 0)
			(unlocked yes)
			(layer "F.Fab")
			(hide yes)
			(effects
				(font
					(size 0.7 0.7)
					(thickness 0.15)
				)
				(justify left bottom)
			)
		)
		(property "MPN" "7760"
			(at 0 0 0)
			(unlocked yes)
			(layer "F.Fab")
			(hide yes)
			(effects
				(font
					(size 1 1)
					(thickness 0.15)
				)
			)
		)
		(property "Manufacturer" "Keystone Electronics"
			(at 0 0 0)
			(unlocked yes)
			(layer "F.Fab")
			(hide yes)
			(effects
				(font
					(size 1 1)
					(thickness 0.15)
				)
			)
		)
		(property "Author" "Antmicro"
			(at 0 0 0)
			(unlocked yes)
			(layer "F.Fab")
			(hide yes)
			(effects
				(font
					(size 1 1)
					(thickness 0.15)
				)
			)
		)
		(property "License" "Apache-2.0"
			(at 0 0 0)
			(unlocked yes)
			(layer "F.Fab")
			(hide yes)
			(effects
				(font
					(size 1 1)
					(thickness 0.15)
				)
			)
		)
		(sheetname "/2xRJ45/")
		(sheetfile "2xrj45.kicad_sch")
		(attr through_hole allow_soldermask_bridges)
		(fp_line
			(start -0.42 3.255)
			(end -0.42 1.745)
			(stroke
				(width 0.15)
				(type solid)
			)
			(layer "F.SilkS")
		)
		(fp_line
			(start -0.42 6.745)
			(end -0.42 10.08)
			(stroke
				(width 0.15)
				(type solid)
			)
			(layer "F.SilkS")
		)
		(fp_line
			(start -0.42 10.08)
			(end 7.91 10.08)
			(stroke
				(width 0.15)
				(type solid)
			)
			(layer "F.SilkS")
		)
		(fp_line
			(start 1.745 -1.4)
			(end 5.745 -1.4)
			(stroke
				(width 0.15)
				(type solid)
			)
			(layer "F.SilkS")
		)
		(fp_line
			(start 7.91 3.255)
			(end 7.91 1.745)
			(stroke
				(width 0.15)
				(type solid)
			)
			(layer "F.SilkS")
		)
		(fp_line
			(start 7.91 10.08)
			(end 7.91 6.745)
			(stroke
				(width 0.15)
				(type solid)
			)
			(layer "F.SilkS")
		)
		(fp_rect
			(start -1.68 -1.68)
			(end 9.16 10.33)
			(stroke
				(width 0.05)
				(type solid)
			)
			(fill no)
			(layer "F.CrtYd")
		)
		(fp_rect
			(start -0.42 -1.4)
			(end 7.91 10.08)
			(stroke
				(width 0.15)
				(type solid)
			)
			(fill no)
			(layer "F.Fab")
		)
		(pad "1" thru_hole circle
			(at 0 0 90)
			(size 2.85 2.85)
			(drill 1.9)
			(layers "*.Cu" "*.Mask")
			(remove_unused_layers no)
			(net 28 "GND")
			(pintype "passive")
		)
		(pad "1" thru_hole circle
			(at 0 5 90)
			(size 2.85 2.85)
			(drill 1.9)
			(layers "*.Cu" "*.Mask")
			(remove_unused_layers no)
			(net 28 "GND")
			(pintype "passive")
		)
		(pad "1" thru_hole circle
			(at 7.49 0 90)
			(size 2.85 2.85)
			(drill 1.9)
			(layers "*.Cu" "*.Mask")
			(remove_unused_layers no)
			(net 28 "GND")
			(pintype "passive")
		)
		(pad "1" thru_hole circle
			(at 7.49 5 90)
			(size 2.85 2.85)
			(drill 1.9)
			(layers "*.Cu" "*.Mask")
			(remove_unused_layers no)
			(net 28 "GND")
			(pintype "passive")
		)
	)
	(footprint "antmicro-footprints:L_Bourns-SRP2512A"
		(layer "F.Cu")
		(at 70.09 103.67)
		(property "Reference" "L11"
			(at -3.68 2.26 180)
			(layer "F.SilkS")
			(effects
				(font
					(size 0.7 0.7)
					(thickness 0.15)
				)
				(justify left bottom)
			)
		)
		(property "Value" "L_4u7_1.55A_Bourns-SRP2512A"
			(at 0 2.25 180)
			(layer "F.Fab")
			(hide yes)
			(effects
				(font
					(size 0.7 0.7)
					(thickness 0.15)
				)
				(justify left bottom)
			)
		)
		(property "Datasheet" "https://www.bourns.com/docs/Product-Datasheets/srp2512a.pdf"
			(at 0 0 0)
			(layer "F.Fab")
			(hide yes)
			(effects
				(font
					(size 1.27 1.27)
					(thickness 0.15)
				)
			)
		)
		(property "Description" "4.7 µH Shielded Drum Core, Wirewound Inductor 1.55 A 235mOhm Max 1008 (2520 Metric)"
			(at 0 0 0)
			(layer "F.Fab")
			(hide yes)
			(effects
				(font
					(size 1.27 1.27)
					(thickness 0.15)
				)
			)
		)
		(property "Val" "4u7/1.55A"
			(at 0 0 0)
			(unlocked yes)
			(layer "F.Fab")
			(hide yes)
			(effects
				(font
					(size 1 1)
					(thickness 0.15)
				)
			)
		)
		(property "Manufacturer" "Bourns"
			(at 0 0 0)
			(unlocked yes)
			(layer "F.Fab")
			(hide yes)
			(effects
				(font
					(size 1 1)
					(thickness 0.15)
				)
			)
		)
		(property "MPN" "SRP2512A-4R7M"
			(at 0 0 0)
			(unlocked yes)
			(layer "F.Fab")
			(hide yes)
			(effects
				(font
					(size 1 1)
					(thickness 0.15)
				)
			)
		)
		(property "ISat" "1.9 A"
			(at 0 0 0)
			(unlocked yes)
			(layer "F.Fab")
			(hide yes)
			(effects
				(font
					(size 1 1)
					(thickness 0.15)
				)
			)
		)
		(property "IMax" "1.55 A"
			(at 0 0 0)
			(unlocked yes)
			(layer "F.Fab")
			(hide yes)
			(effects
				(font
					(size 1 1)
					(thickness 0.15)
				)
			)
		)
		(property "Size" "2.5x2.0"
			(at 0 0 0)
			(unlocked yes)
			(layer "F.Fab")
			(hide yes)
			(effects
				(font
					(size 1 1)
					(thickness 0.15)
				)
			)
		)
		(property "Author" "Antmicro"
			(at 0 0 0)
			(unlocked yes)
			(layer "F.Fab")
			(hide yes)
			(effects
				(font
					(size 1 1)
					(thickness 0.15)
				)
			)
		)
		(property "License" "Apache-2.0"
			(at 0 0 0)
			(unlocked yes)
			(layer "F.Fab")
			(hide yes)
			(effects
				(font
					(size 1 1)
					(thickness 0.15)
				)
			)
		)
		(sheetname "/X710-AT2 power/")
		(sheetfile "x710-at2-power.kicad_sch")
		(attr smd)
		(fp_line
			(start -0.351 1)
			(end 0.349 1)
			(stroke
				(width 0.15)
				(type solid)
			)
			(layer "F.SilkS")
		)
		(fp_line
			(start -0.35 -1)
			(end 0.35 -1)
			(stroke
				(width 0.15)
				(type solid)
			)
			(layer "F.SilkS")
		)
		(fp_rect
			(start -1.65 -1.3)
			(end 1.65 1.3)
			(stroke
				(width 0.05)
				(type solid)
			)
			(fill no)
			(layer "F.CrtYd")
		)
		(pad "1" smd roundrect
			(at -1 0 90)
			(size 2 0.8)
			(layers "F.Cu" "F.Mask" "F.Paste")
			(roundrect_rratio 0.1)
			(net 302 "+1V0")
			(pintype "passive")
		)
		(pad "2" smd roundrect
			(at 1 0 90)
			(size 2 0.8)
			(layers "F.Cu" "F.Mask" "F.Paste")
			(roundrect_rratio 0.1)
			(net 24 "XFI_PVDD")
			(pintype "passive")
		)
	)
	(footprint "antmicro-footprints:R_0402_1005Metric"
		(layer "F.Cu")
		(at 97.4 106.15)
		(descr "Resistor SMD 0402")
		(tags "resistor SMD 0402")
		(property "Reference" "R100"
			(at -2.25 15.425 0)
			(layer "F.SilkS")
			(effects
				(font
					(size 0.7 0.7)
					(thickness 0.15)
				)
				(justify left bottom)
			)
		)
		(property "Value" "R_10k_0402"
			(at -1.011843 1.772046 0)
			(layer "F.Fab")
			(hide yes)
			(effects
				(font
					(size 0.7 0.7)
					(thickness 0.15)
				)
				(justify left bottom)
			)
		)
		(property "Datasheet" "https://www.bourns.com/docs/product-datasheets/cr.pdf"
			(at 0 0 0)
			(layer "F.Fab")
			(hide yes)
			(effects
				(font
					(size 1.27 1.27)
					(thickness 0.15)
				)
			)
		)
		(property "Description" "SMD Chip Resistor, 10 kohm, ± 1%, 62.5 mW, 0402 [1005 Metric], Thick Film, General Purpose"
			(at 0 0 0)
			(layer "F.Fab")
			(hide yes)
			(effects
				(font
					(size 1.27 1.27)
					(thickness 0.15)
				)
			)
		)
		(property "MPN" "CR0402-FX-1002GLF"
			(at 0 0 0)
			(unlocked yes)
			(layer "F.Fab")
			(hide yes)
			(effects
				(font
					(size 1 1)
					(thickness 0.15)
				)
			)
		)
		(property "Manufacturer" "Bourns"
			(at 0 0 0)
			(unlocked yes)
			(layer "F.Fab")
			(hide yes)
			(effects
				(font
					(size 1 1)
					(thickness 0.15)
				)
			)
		)
		(property "License" "Apache-2.0"
			(at 0 0 0)
			(unlocked yes)
			(layer "F.Fab")
			(hide yes)
			(effects
				(font
					(size 1 1)
					(thickness 0.15)
				)
			)
		)
		(property "Author" "Antmicro"
			(at 0 0 0)
			(unlocked yes)
			(layer "F.Fab")
			(hide yes)
			(effects
				(font
					(size 1 1)
					(thickness 0.15)
				)
			)
		)
		(property "Val" "10k"
			(at 0 0 0)
			(unlocked yes)
			(layer "F.Fab")
			(hide yes)
			(effects
				(font
					(size 1 1)
					(thickness 0.15)
				)
			)
		)
		(property "Tolerance" "1%"
			(at 0 0 0)
			(unlocked yes)
			(layer "F.Fab")
			(hide yes)
			(effects
				(font
					(size 1 1)
					(thickness 0.15)
				)
			)
		)
		(sheetname "/X710-AT2 Misc/")
		(sheetfile "x710-at2-mics.kicad_sch")
		(attr smd)
		(fp_rect
			(start -0.925 -0.47)
			(end 0.925 0.47)
			(stroke
				(width 0.05)
				(type default)
			)
			(fill no)
			(layer "F.CrtYd")
		)
		(fp_rect
			(start -0.5 -0.25)
			(end 0.5 0.25)
			(stroke
				(width 0.15)
				(type solid)
			)
			(fill no)
			(layer "F.Fab")
		)
		(pad "1" smd roundrect
			(at -0.48 0)
			(size 0.59 0.64)
			(layers "F.Cu" "F.Mask" "F.Paste")
			(roundrect_rratio 0.25)
			(net 290 "/X710-AT2 Misc/~{DEV_DIS}")
			(pintype "passive")
		)
		(pad "2" smd roundrect
			(at 0.48 0)
			(size 0.59 0.64)
			(layers "F.Cu" "F.Mask" "F.Paste")
			(roundrect_rratio 0.25)
			(net 7 "+3V3")
			(pintype "passive")
		)
	)
	(footprint "antmicro-footprints:C_0603_1608Metric_EIA"
		(layer "F.Cu")
		(at 53.25 111.6 -90)
		(descr "Capacitor SMD 0603, IPC-7351 Density Level A")
		(tags "Capacitor 0603")
		(property "Reference" "C31"
			(at 1.01 0.47 90)
			(layer "F.SilkS")
			(effects
				(font
					(size 0.7 0.7)
					(thickness 0.15)
				)
				(justify right top)
			)
		)
		(property "Value" "C_22u_16V_0603"
			(at -1.42757 1.770288 90)
			(layer "F.Fab")
			(hide yes)
			(effects
				(font
					(size 0.7 0.7)
					(thickness 0.15)
				)
				(justify right top)
			)
		)
		(property "Datasheet" "https://product.samsungsem.com/mlcc/CL10A226MO7JZN.do"
			(at 0 0 90)
			(layer "F.Fab")
			(hide yes)
			(effects
				(font
					(size 1.27 1.27)
					(thickness 0.15)
				)
			)
		)
		(property "Description" "SMD Multilayer Ceramic Capacitor"
			(at 0 0 90)
			(layer "F.Fab")
			(hide yes)
			(effects
				(font
					(size 1.27 1.27)
					(thickness 0.15)
				)
			)
		)
		(property "MPN" "CL10A226MO7JZNC"
			(at 0 0 270)
			(unlocked yes)
			(layer "F.Fab")
			(hide yes)
			(effects
				(font
					(size 1 1)
					(thickness 0.15)
				)
			)
		)
		(property "Manufacturer" "Samsung Electro-Mechanics"
			(at 0 0 270)
			(unlocked yes)
			(layer "F.Fab")
			(hide yes)
			(effects
				(font
					(size 1 1)
					(thickness 0.15)
				)
			)
		)
		(property "License" "Apache-2.0"
			(at 0 0 270)
			(unlocked yes)
			(layer "F.Fab")
			(hide yes)
			(effects
				(font
					(size 1 1)
					(thickness 0.15)
				)
			)
		)
		(property "Author" "Antmicro"
			(at 0 0 270)
			(unlocked yes)
			(layer "F.Fab")
			(hide yes)
			(effects
				(font
					(size 1 1)
					(thickness 0.15)
				)
			)
		)
		(property "Val" "22u"
			(at 0 0 270)
			(unlocked yes)
			(layer "F.Fab")
			(hide yes)
			(effects
				(font
					(size 1 1)
					(thickness 0.15)
				)
			)
		)
		(property "Voltage" "16V"
			(at 0 0 270)
			(unlocked yes)
			(layer "F.Fab")
			(hide yes)
			(effects
				(font
					(size 1 1)
					(thickness 0.15)
				)
			)
		)
		(property "Dielectric" ""
			(at 0 0 270)
			(unlocked yes)
			(layer "F.Fab")
			(hide yes)
			(effects
				(font
					(size 1 1)
					(thickness 0.15)
				)
			)
		)
		(property "Public" "False"
			(at 0 0 270)
			(unlocked yes)
			(layer "F.Fab")
			(hide yes)
			(effects
				(font
					(size 1 1)
					(thickness 0.15)
				)
			)
		)
		(sheetname "/Power/")
		(sheetfile "power.kicad_sch")
		(attr smd)
		(fp_line
			(start -0.15 0.55)
			(end 0.15 0.55)
			(stroke
				(width 0.15)
				(type solid)
			)
			(layer "F.SilkS")
		)
		(fp_line
			(start -0.15 -0.55)
			(end 0.15 -0.55)
			(stroke
				(width 0.15)
				(type solid)
			)
			(layer "F.SilkS")
		)
		(fp_rect
			(start -1.25 -0.65)
			(end 1.25 0.65)
			(stroke
				(width 0.05)
				(type solid)
			)
			(fill no)
			(layer "F.CrtYd")
		)
		(fp_rect
			(start -0.8 -0.45)
			(end 0.8 0.45)
			(stroke
				(width 0.15)
				(type solid)
			)
			(fill no)
			(layer "F.Fab")
		)
		(pad "1" smd roundrect
			(at -0.7 0 270)
			(size 0.8 1.1)
			(layers "F.Cu" "F.Mask" "F.Paste")
			(roundrect_rratio 0.2)
			(net 28 "GND")
			(pintype "passive")
		)
		(pad "2" smd roundrect
			(at 0.7 0 270)
			(size 0.8 1.1)
			(layers "F.Cu" "F.Mask" "F.Paste")
			(roundrect_rratio 0.2)
			(net 314 "VCC")
			(pintype "passive")
		)
	)
)
